# S9S_MB_2U (Grand Teton) — schematic netlist excerpt (pin names and nets, part order shuffled) for the footprints in the layout excerpt that follows; sources: Cadence DE-HDL packaged netlist, KiCad conversion of 03242023_DA0F0TMBIJ0_F0T_Motherboard_J_brd_V01_OCP.brd

PC2144  Q_CAP  0.01UF 50V 10% EMPTY  pkg C0402  page 156 : A = P3V3_OCP_SFF_R ; B = P3V3_OCP_GATE_PU202_1
PC2092  Q_CAP  0.1UF 25V 10% X7R  pkg 0402  page 156 : A = P12V_OCP_SFF ; B = GND

(kicad_pcb
	(version 20260206)
	(generator "pcbnew")
	(generator_version "10.0")
	(general
		(thickness 1.6)
		(legacy_teardrops no)
	)
	(paper "A4")
	(title_block
		(title "03242023_DA0F0TMBIJ0_F0T_Motherboard_J_brd_V01_OCP.brd")
		(comment 1 "Grand Teton / footprints 1227-1228 of 6105")
	)
	(layers
		(0 "F.Cu" signal "TOP")
		(4 "In1.Cu" signal "GND")
		(6 "In2.Cu" signal "IN1")
		(8 "In3.Cu" signal "GND1")
		(10 "In4.Cu" signal "IN2")
		(12 "In5.Cu" signal "GND2")
		(14 "In6.Cu" signal "IN3")
		(16 "In7.Cu" signal "GND3")
		(18 "In8.Cu" signal "VCC")
		(20 "In9.Cu" signal "VCC1")
		(22 "In10.Cu" signal "GND4")
		(24 "In11.Cu" signal "IN4")
		(26 "In12.Cu" signal "GND5")
		(28 "In13.Cu" signal "IN5")
		(30 "In14.Cu" signal "GND6")
		(32 "In15.Cu" signal "IN6")
		(34 "In16.Cu" signal "GND7")
		(2 "B.Cu" signal "BOTTOM")
		(9 "F.Adhes" user "F.Adhesive")
		(11 "B.Adhes" user "B.Adhesive")
		(13 "F.Paste" user "Package Geometry/Pastemask Top")
		(15 "B.Paste" user "Package Geometry/Pastemask Bottom")
		(5 "F.SilkS" user "Ref Des/Silkscreen Top")
		(7 "B.SilkS" user "Ref Des/Silkscreen Bottom")
		(1 "F.Mask" user "Board Geometry/Soldermask Top")
		(3 "B.Mask" user "Board Geometry/Soldermask Bottom")
		(17 "Dwgs.User" user "User.Drawings")
		(19 "Cmts.User" user "User.Comments")
		(21 "Eco1.User" user "User.Eco1")
		(23 "Eco2.User" user "User.Eco2")
		(25 "Edge.Cuts" user "Board Geometry/Outline")
		(27 "Margin" user)
		(31 "F.CrtYd" user "Package Geometry/Place Bound Top")
		(29 "B.CrtYd" user "Package Geometry/Place Bound Bottom")
		(35 "F.Fab" user "Ref Des/Assembly Top")
		(33 "B.Fab" user "Ref Des/Assembly Bottom")
	)
	(footprint ""
		(layer "F.Cu")
		(at 435.621176 -103.77043 90)
		(property "Reference" "PC2144"
			(at 0 0 90)
			(layer "F.SilkS")
			(hide yes)
			(effects
				(font
					(size 1.27 1.27)
				)
			)
		)
		(property "Value" ""
			(at 0 0 90)
			(layer "F.Fab")
			(effects
				(font
					(size 1.27 1.27)
				)
			)
		)
		(duplicate_pad_numbers_are_jumpers no)
		(fp_line
			(start 0.7874 -0.4064)
			(end 0.7874 0.4064)
			(stroke
				(width 0.1524)
				(type default)
			)
			(layer "F.SilkS")
		)
		(fp_line
			(start -0.7874 -0.4064)
			(end 0.7874 -0.4064)
			(stroke
				(width 0.1524)
				(type default)
			)
			(layer "F.SilkS")
		)
		(fp_line
			(start 0.7874 0.4064)
			(end -0.7874 0.4064)
			(stroke
				(width 0.1524)
				(type default)
			)
			(layer "F.SilkS")
		)
		(fp_line
			(start -0.7874 0.4064)
			(end -0.7874 -0.4064)
			(stroke
				(width 0.1524)
				(type default)
			)
			(layer "F.SilkS")
		)
		(fp_line
			(start -0.12065 -0.305054)
			(end -0.12065 -0.2794)
			(stroke
				(width 0.1)
				(type default)
			)
			(layer "F.Fab")
		)
		(fp_line
			(start -0.67945 -0.305054)
			(end -0.12065 -0.305054)
			(stroke
				(width 0.1)
				(type default)
			)
			(layer "F.Fab")
		)
		(fp_line
			(start 0.67945 -0.3048)
			(end 0.67945 0.3048)
			(stroke
				(width 0.1)
				(type default)
			)
			(layer "F.Fab")
		)
		(fp_line
			(start 0.12065 -0.3048)
			(end 0.67945 -0.3048)
			(stroke
				(width 0.1)
				(type default)
			)
			(layer "F.Fab")
		)
		(fp_line
			(start 0.12065 -0.2794)
			(end 0.12065 -0.3048)
			(stroke
				(width 0.1)
				(type default)
			)
			(layer "F.Fab")
		)
		(fp_line
			(start -0.12065 -0.2794)
			(end 0.12065 -0.2794)
			(stroke
				(width 0.1)
				(type default)
			)
			(layer "F.Fab")
		)
		(fp_line
			(start 0.120396 0.2794)
			(end -0.12065 0.2794)
			(stroke
				(width 0.1)
				(type default)
			)
			(layer "F.Fab")
		)
		(fp_line
			(start -0.12065 0.2794)
			(end -0.12065 0.3048)
			(stroke
				(width 0.1)
				(type default)
			)
			(layer "F.Fab")
		)
		(fp_line
			(start 0.67945 0.3048)
			(end 0.120396 0.3048)
			(stroke
				(width 0.1)
				(type default)
			)
			(layer "F.Fab")
		)
		(fp_line
			(start 0.120396 0.3048)
			(end 0.120396 0.2794)
			(stroke
				(width 0.1)
				(type default)
			)
			(layer "F.Fab")
		)
		(fp_line
			(start -0.12065 0.3048)
			(end -0.67945 0.3048)
			(stroke
				(width 0.1)
				(type default)
			)
			(layer "F.Fab")
		)
		(fp_line
			(start -0.67945 0.3048)
			(end -0.67945 -0.305054)
			(stroke
				(width 0.1)
				(type default)
			)
			(layer "F.Fab")
		)
		(pad "1" smd circle
			(at -0.40005 0 90)
			(size 0 0)
			(layers "F.Cu" "F.Mask" "F.Paste")
			(net "P3V3_OCP_SFF_R")
		)
		(pad "2" smd circle
			(at 0.40005 0 90)
			(size 0 0)
			(layers "F.Cu" "F.Mask" "F.Paste")
			(net "P3V3_OCP_GATE_PU202_1")
		)
	)
	(footprint ""
		(layer "F.Cu")
		(at 440.384438 -14.593316 180)
		(property "Reference" "PC2092"
			(at 0 0 180)
			(layer "F.SilkS")
			(hide yes)
			(effects
				(font
					(size 1.27 1.27)
				)
			)
		)
		(property "Value" ""
			(at 0 0 180)
			(layer "F.Fab")
			(effects
				(font
					(size 1.27 1.27)
				)
			)
		)
		(duplicate_pad_numbers_are_jumpers no)
		(fp_line
			(start 0.7874 0.4064)
			(end -0.7874 0.4064)
			(stroke
				(width 0.1524)
				(type default)
			)
			(layer "F.SilkS")
		)
		(fp_line
			(start 0.7874 -0.4064)
			(end 0.7874 0.4064)
			(stroke
				(width 0.1524)
				(type default)
			)
			(layer "F.SilkS")
		)
		(fp_line
			(start -0.7874 0.4064)
			(end -0.7874 -0.4064)
			(stroke
				(width 0.1524)
				(type default)
			)
			(layer "F.SilkS")
		)
		(fp_line
			(start -0.7874 -0.4064)
			(end 0.7874 -0.4064)
			(stroke
				(width 0.1524)
				(type default)
			)
			(layer "F.SilkS")
		)
		(fp_line
			(start 0.67945 0.3048)
			(end 0.120396 0.3048)
			(stroke
				(width 0.1)
				(type default)
			)
			(layer "F.Fab")
		)
		(fp_line
			(start 0.67945 -0.3048)
			(end 0.67945 0.3048)
			(stroke
				(width 0.1)
				(type default)
			)
			(layer "F.Fab")
		)
		(fp_line
			(start 0.12065 -0.2794)
			(end 0.12065 -0.3048)
			(stroke
				(width 0.1)
				(type default)
			)
			(layer "F.Fab")
		)
		(fp_line
			(start 0.12065 -0.3048)
			(end 0.67945 -0.3048)
			(stroke
				(width 0.1)
				(type default)
			)
			(layer "F.Fab")
		)
		(fp_line
			(start 0.120396 0.3048)
			(end 0.120396 0.2794)
			(stroke
				(width 0.1)
				(type default)
			)
			(layer "F.Fab")
		)
		(fp_line
			(start 0.120396 0.2794)
			(end -0.12065 0.2794)
			(stroke
				(width 0.1)
				(type default)
			)
			(layer "F.Fab")
		)
		(fp_line
			(start -0.12065 0.3048)
			(end -0.67945 0.3048)
			(stroke
				(width 0.1)
				(type default)
			)
			(layer "F.Fab")
		)
		(fp_line
			(start -0.12065 0.2794)
			(end -0.12065 0.3048)
			(stroke
				(width 0.1)
				(type default)
			)
			(layer "F.Fab")
		)
		(fp_line
			(start -0.12065 -0.2794)
			(end 0.12065 -0.2794)
			(stroke
				(width 0.1)
				(type default)
			)
			(layer "F.Fab")
		)
		(fp_line
			(start -0.12065 -0.305054)
			(end -0.12065 -0.2794)
			(stroke
				(width 0.1)
				(type default)
			)
			(layer "F.Fab")
		)
		(fp_line
			(start -0.67945 0.3048)
			(end -0.67945 -0.305054)
			(stroke
				(width 0.1)
				(type default)
			)
			(layer "F.Fab")
		)
		(fp_line
			(start -0.67945 -0.305054)
			(end -0.12065 -0.305054)
			(stroke
				(width 0.1)
				(type default)
			)
			(layer "F.Fab")
		)
		(pad "1" smd circle
			(at -0.40005 0 180)
			(size 0 0)
			(layers "F.Cu" "F.Mask" "F.Paste")
			(net "P12V_OCP_SFF")
		)
		(pad "2" smd circle
			(at 0.40005 0 180)
			(size 0 0)
			(layers "F.Cu" "F.Mask" "F.Paste")
			(net "GND")
		)
	)
)
